# S9S_MB_2U (Grand Teton) — schematic netlist excerpt (pin names and nets, part order shuffled) for the footprints in the layout excerpt that follows; sources: Cadence DE-HDL packaged netlist, KiCad conversion of 03242023_DA0F0TMBIJ0_F0T_Motherboard_J_brd_V01_OCP.brd

C568  Q_CAP  0.1UF 25V 10% X7R  pkg 0402  page 236 : A = PVNN_TERM_CPU1 ; B = GND
C2345  Q_CAP  0.1UF 25V 10% X7R  pkg 0402  page 161 : A = P3V3_AUX ; B = GND

(kicad_pcb
	(version 20260206)
	(generator "pcbnew")
	(generator_version "10.0")
	(general
		(thickness 1.6)
		(legacy_teardrops no)
	)
	(paper "A4")
	(title_block
		(title "03242023_DA0F0TMBIJ0_F0T_Motherboard_J_brd_V01_OCP.brd")
		(comment 1 "Grand Teton / footprints 349-350 of 6105")
	)
	(layers
		(0 "F.Cu" signal "TOP")
		(4 "In1.Cu" signal "GND")
		(6 "In2.Cu" signal "IN1")
		(8 "In3.Cu" signal "GND1")
		(10 "In4.Cu" signal "IN2")
		(12 "In5.Cu" signal "GND2")
		(14 "In6.Cu" signal "IN3")
		(16 "In7.Cu" signal "GND3")
		(18 "In8.Cu" signal "VCC")
		(20 "In9.Cu" signal "VCC1")
		(22 "In10.Cu" signal "GND4")
		(24 "In11.Cu" signal "IN4")
		(26 "In12.Cu" signal "GND5")
		(28 "In13.Cu" signal "IN5")
		(30 "In14.Cu" signal "GND6")
		(32 "In15.Cu" signal "IN6")
		(34 "In16.Cu" signal "GND7")
		(2 "B.Cu" signal "BOTTOM")
		(9 "F.Adhes" user "F.Adhesive")
		(11 "B.Adhes" user "B.Adhesive")
		(13 "F.Paste" user "Package Geometry/Pastemask Top")
		(15 "B.Paste" user "Package Geometry/Pastemask Bottom")
		(5 "F.SilkS" user "Ref Des/Silkscreen Top")
		(7 "B.SilkS" user "Ref Des/Silkscreen Bottom")
		(1 "F.Mask" user "Board Geometry/Soldermask Top")
		(3 "B.Mask" user "Board Geometry/Soldermask Bottom")
		(17 "Dwgs.User" user "User.Drawings")
		(19 "Cmts.User" user "User.Comments")
		(21 "Eco1.User" user "User.Eco1")
		(23 "Eco2.User" user "User.Eco2")
		(25 "Edge.Cuts" user "Board Geometry/Outline")
		(27 "Margin" user)
		(31 "F.CrtYd" user "Package Geometry/Place Bound Top")
		(29 "B.CrtYd" user "Package Geometry/Place Bound Bottom")
		(35 "F.Fab" user "Ref Des/Assembly Top")
		(33 "B.Fab" user "Ref Des/Assembly Bottom")
	)
	(footprint ""
		(layer "F.Cu")
		(at 223.716088 -223.09709 -90)
		(property "Reference" "C568"
			(at 0 0 270)
			(layer "F.SilkS")
			(hide yes)
			(effects
				(font
					(size 1.27 1.27)
				)
			)
		)
		(property "Value" ""
			(at 0 0 270)
			(layer "F.Fab")
			(effects
				(font
					(size 1.27 1.27)
				)
			)
		)
		(duplicate_pad_numbers_are_jumpers no)
		(fp_line
			(start -0.7874 0.4064)
			(end -0.7874 -0.4064)
			(stroke
				(width 0.1524)
				(type default)
			)
			(layer "F.SilkS")
		)
		(fp_line
			(start 0.7874 0.4064)
			(end -0.7874 0.4064)
			(stroke
				(width 0.1524)
				(type default)
			)
			(layer "F.SilkS")
		)
		(fp_line
			(start -0.7874 -0.4064)
			(end 0.7874 -0.4064)
			(stroke
				(width 0.1524)
				(type default)
			)
			(layer "F.SilkS")
		)
		(fp_line
			(start 0.7874 -0.4064)
			(end 0.7874 0.4064)
			(stroke
				(width 0.1524)
				(type default)
			)
			(layer "F.SilkS")
		)
		(fp_line
			(start -0.67945 0.3048)
			(end -0.67945 -0.305054)
			(stroke
				(width 0.1)
				(type default)
			)
			(layer "F.Fab")
		)
		(fp_line
			(start -0.12065 0.3048)
			(end -0.67945 0.3048)
			(stroke
				(width 0.1)
				(type default)
			)
			(layer "F.Fab")
		)
		(fp_line
			(start 0.120396 0.3048)
			(end 0.120396 0.2794)
			(stroke
				(width 0.1)
				(type default)
			)
			(layer "F.Fab")
		)
		(fp_line
			(start 0.67945 0.3048)
			(end 0.120396 0.3048)
			(stroke
				(width 0.1)
				(type default)
			)
			(layer "F.Fab")
		)
		(fp_line
			(start -0.12065 0.2794)
			(end -0.12065 0.3048)
			(stroke
				(width 0.1)
				(type default)
			)
			(layer "F.Fab")
		)
		(fp_line
			(start 0.120396 0.2794)
			(end -0.12065 0.2794)
			(stroke
				(width 0.1)
				(type default)
			)
			(layer "F.Fab")
		)
		(fp_line
			(start -0.12065 -0.2794)
			(end 0.12065 -0.2794)
			(stroke
				(width 0.1)
				(type default)
			)
			(layer "F.Fab")
		)
		(fp_line
			(start 0.12065 -0.2794)
			(end 0.12065 -0.3048)
			(stroke
				(width 0.1)
				(type default)
			)
			(layer "F.Fab")
		)
		(fp_line
			(start 0.12065 -0.3048)
			(end 0.67945 -0.3048)
			(stroke
				(width 0.1)
				(type default)
			)
			(layer "F.Fab")
		)
		(fp_line
			(start 0.67945 -0.3048)
			(end 0.67945 0.3048)
			(stroke
				(width 0.1)
				(type default)
			)
			(layer "F.Fab")
		)
		(fp_line
			(start -0.67945 -0.305054)
			(end -0.12065 -0.305054)
			(stroke
				(width 0.1)
				(type default)
			)
			(layer "F.Fab")
		)
		(fp_line
			(start -0.12065 -0.305054)
			(end -0.12065 -0.2794)
			(stroke
				(width 0.1)
				(type default)
			)
			(layer "F.Fab")
		)
		(pad "1" smd circle
			(at -0.40005 0 270)
			(size 0 0)
			(layers "F.Cu" "F.Mask" "F.Paste")
			(net "PVNN_TERM_CPU1")
		)
		(pad "2" smd circle
			(at 0.40005 0 270)
			(size 0 0)
			(layers "F.Cu" "F.Mask" "F.Paste")
			(net "GND")
		)
	)
	(footprint ""
		(layer "F.Cu")
		(at 366.4458 -15.255748 180)
		(property "Reference" "C2345"
			(at 0 0 180)
			(layer "F.SilkS")
			(hide yes)
			(effects
				(font
					(size 1.27 1.27)
				)
			)
		)
		(property "Value" ""
			(at 0 0 180)
			(layer "F.Fab")
			(effects
				(font
					(size 1.27 1.27)
				)
			)
		)
		(duplicate_pad_numbers_are_jumpers no)
		(fp_line
			(start 0.7874 0.4064)
			(end -0.7874 0.4064)
			(stroke
				(width 0.1524)
				(type default)
			)
			(layer "F.SilkS")
		)
		(fp_line
			(start 0.7874 -0.4064)
			(end 0.7874 0.4064)
			(stroke
				(width 0.1524)
				(type default)
			)
			(layer "F.SilkS")
		)
		(fp_line
			(start -0.7874 0.4064)
			(end -0.7874 -0.4064)
			(stroke
				(width 0.1524)
				(type default)
			)
			(layer "F.SilkS")
		)
		(fp_line
			(start -0.7874 -0.4064)
			(end 0.7874 -0.4064)
			(stroke
				(width 0.1524)
				(type default)
			)
			(layer "F.SilkS")
		)
		(fp_line
			(start 0.67945 0.3048)
			(end 0.120396 0.3048)
			(stroke
				(width 0.1)
				(type default)
			)
			(layer "F.Fab")
		)
		(fp_line
			(start 0.67945 -0.3048)
			(end 0.67945 0.3048)
			(stroke
				(width 0.1)
				(type default)
			)
			(layer "F.Fab")
		)
		(fp_line
			(start 0.12065 -0.2794)
			(end 0.12065 -0.3048)
			(stroke
				(width 0.1)
				(type default)
			)
			(layer "F.Fab")
		)
		(fp_line
			(start 0.12065 -0.3048)
			(end 0.67945 -0.3048)
			(stroke
				(width 0.1)
				(type default)
			)
			(layer "F.Fab")
		)
		(fp_line
			(start 0.120396 0.3048)
			(end 0.120396 0.2794)
			(stroke
				(width 0.1)
				(type default)
			)
			(layer "F.Fab")
		)
		(fp_line
			(start 0.120396 0.2794)
			(end -0.12065 0.2794)
			(stroke
				(width 0.1)
				(type default)
			)
			(layer "F.Fab")
		)
		(fp_line
			(start -0.12065 0.3048)
			(end -0.67945 0.3048)
			(stroke
				(width 0.1)
				(type default)
			)
			(layer "F.Fab")
		)
		(fp_line
			(start -0.12065 0.2794)
			(end -0.12065 0.3048)
			(stroke
				(width 0.1)
				(type default)
			)
			(layer "F.Fab")
		)
		(fp_line
			(start -0.12065 -0.2794)
			(end 0.12065 -0.2794)
			(stroke
				(width 0.1)
				(type default)
			)
			(layer "F.Fab")
		)
		(fp_line
			(start -0.12065 -0.305054)
			(end -0.12065 -0.2794)
			(stroke
				(width 0.1)
				(type default)
			)
			(layer "F.Fab")
		)
		(fp_line
			(start -0.67945 0.3048)
			(end -0.67945 -0.305054)
			(stroke
				(width 0.1)
				(type default)
			)
			(layer "F.Fab")
		)
		(fp_line
			(start -0.67945 -0.305054)
			(end -0.12065 -0.305054)
			(stroke
				(width 0.1)
				(type default)
			)
			(layer "F.Fab")
		)
		(pad "1" smd circle
			(at -0.40005 0 180)
			(size 0 0)
			(layers "F.Cu" "F.Mask" "F.Paste")
			(net "P3V3_AUX")
		)
		(pad "2" smd circle
			(at 0.40005 0 180)
			(size 0 0)
			(layers "F.Cu" "F.Mask" "F.Paste")
			(net "GND")
		)
	)
)
